FILE_TYPE = CONNECTIVITY;
{Allegro Design Entry HDL 16.6-p007 (v16-6-112F) 10/10/2012}
"PAGE_NUMBER" = 271;
0"NC";
1"GND\g";
2"GND\g";
3"GND\g";
4"GND\g";
5"GND\g";
6"GND\g";
7"GND\g";
8"GND\g";
9"GND\g";
10"GND\g";
11"GND\g";
12"GND\g";
13"GND\g";
14"GND\g";
15"GND\g";
16"GND\g";
17"GND\g";
18"GND\g";
19"GND\g";
20"GND\g";
21"GND\g";
22"GND\g";
23"GND\g";
24"GND\g";
25"GND\g";
26"GND\g";
27"GND\g";
28"GND\g";
29"GND\g";
30"GND\g";
31"L3_85OHM_6INCH_DN";
32"L5_40OHM_6INCH";
33"L1_95OHM_6INCH_DN";
34"L1_95OHM_6INCH_DP";
35"L12_95OHM_6INCH_DP";
36"L12_95OHM_6INCH_DN";
37"L1_50OHM_6INCH";
38"L3_50OHM_6INCH";
39"L14_50OHM_6INCH";
40"L12_50OHM_6INCH";
41"L10_50OHM_6INCH";
42"L14_100OHM_6INCH_DP";
43"L3_73OHM_6INCH_DP";
44"L3_73OHM_6INCH_DN";
45"L5_73OHM_6INCH_DP";
46"L5_50OHM_6INCH";
47"L12_85OHM_6INCH_DP";
48"L10_85OHM_6INCH_DP";
49"L10_85OHM_6INCH_DN";
50"L12_85OHM_6INCH_DN";
51"L1_40OHM_6INCH";
52"L14_40OHM_6INCH";
53"L12_40OHM_6INCH";
54"L10_40OHM_6INCH";
55"L3_40OHM_6INCH";
56"L10_73OHM_6INCH_DN";
57"L12_73OHM_6INCH_DN";
58"L14_73OHM_6INCH_DP";
59"L14_73OHM_6INCH_DN";
60"L14_85OHM_6INCH_DN";
61"L14_85OHM_6INCH_DP";
62"L1_85OHM_6INCH_DP";
63"L1_85OHM_6INCH_DN";
64"L5_85OHM_6INCH_DP";
65"L5_85OHM_6INCH_DN";
66"L3_85OHM_6INCH_DP";
67"L14_100OHM_6INCH_DN";
68"L10_100OHM_6INCH_DP";
69"L12_100OHM_6INCH_DN";
70"L12_100OHM_6INCH_DP";
71"L1_73OHM_6INCH_DP";
72"L1_73OHM_6INCH_DN";
73"L5_73OHM_6INCH_DN";
74"L10_73OHM_6INCH_DP";
75"L12_73OHM_6INCH_DP";
76"L10_100OHM_6INCH_DN";
77"L1_100OHM_6INCH_DN";
78"L1_100OHM_6INCH_DP";
%"GND"
"1","(-8425,4775)","0","mstr_symbols","I10";
;
VOLTAGE"0.0V"
SIZE"1B"
BODY_TYPE"PLUMBING"
HDL_POWER"GND"
CDS_LIB"mstr_symbols";
"A\NAC"1;
%"TPAD-DIFF-4P-GP"
"1","(-7950,4575)","0","w_hdl","I11";
;
CDS_SEC"1"
CDS_LOCATION"T1P5"
LOCATION"T1P5"
VALUE"TPAD-DIFF-4P-GP"
PART_NUMBER"ZZ.00PAD.NW1"
CDS_LMAN_SYM_OUTLINE"-75,100,75,-100"
CDS_LIB"w_hdl"
PACK_TYPE"DISCRET-GB3"
SEC"1"
SEC_TYPE"DISCRET-GB3";
"GND2"
$PN"GND2"2;
"GND1"
$PN"GND1"2;
"2"
$PN"2"50;
"1"
$PN"1"47;
%"GND"
"1","(-8400,4425)","0","mstr_symbols","I12";
;
VOLTAGE"0.0V"
SIZE"1B"
BODY_TYPE"PLUMBING"
HDL_POWER"GND"
CDS_LIB"mstr_symbols";
"A\NAC"2;
%"TPAD-DIFF-4P-GP"
"1","(-7950,4175)","0","w_hdl","I13";
;
CDS_SEC"1"
CDS_LOCATION"T1P6"
LOCATION"T1P6"
VALUE"TPAD-DIFF-4P-GP"
PART_NUMBER"ZZ.00PAD.NW1"
CDS_LMAN_SYM_OUTLINE"-75,100,75,-100"
CDS_LIB"w_hdl"
PACK_TYPE"DISCRET-GB3"
SEC"1"
SEC_TYPE"DISCRET-GB3";
"GND2"
$PN"GND2"3;
"GND1"
$PN"GND1"3;
"2"
$PN"2"60;
"1"
$PN"1"61;
%"GND"
"1","(-8400,4025)","0","mstr_symbols","I14";
;
CDS_LIB"mstr_symbols"
VOLTAGE"0.0V"
SIZE"1B"
BODY_TYPE"PLUMBING"
HDL_POWER"GND";
"A\NAC"3;
%"TPAD-DIFF-4P-GP"
"1","(-6000,4900)","0","w_hdl","I15";
;
CDS_SEC"1"
CDS_LOCATION"T1P10"
LOCATION"T1P10"
VALUE"TPAD-DIFF-4P-GP"
PART_NUMBER"ZZ.00PAD.NW1"
CDS_LMAN_SYM_OUTLINE"-75,100,75,-100"
CDS_LIB"w_hdl"
PACK_TYPE"DISCRET-GB3"
SEC"1"
SEC_TYPE"DISCRET-GB3";
"GND2"
$PN"GND2"7;
"GND1"
$PN"GND1"7;
"2"
$PN"2"56;
"1"
$PN"1"74;
%"TPAD-DIFF-4P-GP"
"1","(-6000,5675)","0","w_hdl","I16";
;
CDS_SEC"1"
CDS_LOCATION"T1P8"
LOCATION"T1P8"
VALUE"TPAD-DIFF-4P-GP"
PART_NUMBER"ZZ.00PAD.NW1"
CDS_LMAN_SYM_OUTLINE"-75,100,75,-100"
CDS_LIB"w_hdl"
PACK_TYPE"DISCRET-GB3"
SEC"1"
SEC_TYPE"DISCRET-GB3";
"GND2"
$PN"GND2"5;
"GND1"
$PN"GND1"5;
"2"
$PN"2"44;
"1"
$PN"1"43;
%"TPAD-DIFF-4P-GP"
"1","(-6000,6075)","0","w_hdl","I17";
;
CDS_SEC"1"
CDS_LOCATION"T1P7"
LOCATION"T1P7"
VALUE"TPAD-DIFF-4P-GP"
PART_NUMBER"ZZ.00PAD.NW1"
CDS_LMAN_SYM_OUTLINE"-75,100,75,-100"
CDS_LIB"w_hdl"
PACK_TYPE"DISCRET-GB3"
SEC"1"
SEC_TYPE"DISCRET-GB3";
"GND2"
$PN"GND2"4;
"GND1"
$PN"GND1"4;
"2"
$PN"2"72;
"1"
$PN"1"71;
%"GND"
"1","(-6450,5925)","0","mstr_symbols","I18";
;
VOLTAGE"0.0V"
SIZE"1B"
BODY_TYPE"PLUMBING"
HDL_POWER"GND"
CDS_LIB"mstr_symbols";
"A\NAC"4;
%"TPAD-DIFF-4P-GP"
"1","(-6000,5300)","0","w_hdl","I19";
;
CDS_SEC"1"
CDS_LOCATION"T1P9"
VALUE"TPAD-DIFF-4P-GP"
LOCATION"T1P9"
PART_NUMBER"ZZ.00PAD.NW1"
CDS_LMAN_SYM_OUTLINE"-75,100,75,-100"
CDS_LIB"w_hdl"
PACK_TYPE"DISCRET-GB3"
SEC"1"
SEC_TYPE"DISCRET-GB3";
"GND2"
$PN"GND2"6;
"GND1"
$PN"GND1"6;
"2"
$PN"2"73;
"1"
$PN"1"45;
%"GND"
"1","(-6450,5525)","0","mstr_symbols","I20";
;
VOLTAGE"0.0V"
SIZE"1B"
BODY_TYPE"PLUMBING"
HDL_POWER"GND"
CDS_LIB"mstr_symbols";
"A\NAC"5;
%"GND"
"1","(-6450,5150)","0","mstr_symbols","I21";
;
VOLTAGE"0.0V"
SIZE"1B"
BODY_TYPE"PLUMBING"
HDL_POWER"GND"
CDS_LIB"mstr_symbols";
"A\NAC"6;
%"GND"
"1","(-6450,4750)","0","mstr_symbols","I22";
;
VOLTAGE"0.0V"
SIZE"1B"
BODY_TYPE"PLUMBING"
HDL_POWER"GND"
CDS_LIB"mstr_symbols";
"A\NAC"7;
%"TPAD-DIFF-4P-GP"
"1","(-5975,4550)","0","w_hdl","I23";
;
CDS_SEC"1"
CDS_LOCATION"T1P11"
LOCATION"T1P11"
VALUE"TPAD-DIFF-4P-GP"
PART_NUMBER"ZZ.00PAD.NW1"
CDS_LMAN_SYM_OUTLINE"-75,100,75,-100"
CDS_LIB"w_hdl"
PACK_TYPE"DISCRET-GB3"
SEC"1"
SEC_TYPE"DISCRET-GB3";
"GND2"
$PN"GND2"8;
"GND1"
$PN"GND1"8;
"2"
$PN"2"57;
"1"
$PN"1"75;
%"TPAD-DIFF-4P-GP"
"1","(-5975,4150)","0","w_hdl","I24";
;
CDS_SEC"1"
CDS_LOCATION"T1P12"
LOCATION"T1P12"
VALUE"TPAD-DIFF-4P-GP"
PART_NUMBER"ZZ.00PAD.NW1"
CDS_LMAN_SYM_OUTLINE"-75,100,75,-100"
CDS_LIB"w_hdl"
PACK_TYPE"DISCRET-GB3"
SEC"1"
SEC_TYPE"DISCRET-GB3";
"GND2"
$PN"GND2"9;
"GND1"
$PN"GND1"9;
"2"
$PN"2"59;
"1"
$PN"1"58;
%"GND"
"1","(-6425,4400)","0","mstr_symbols","I25";
;
VOLTAGE"0.0V"
SIZE"1B"
BODY_TYPE"PLUMBING"
HDL_POWER"GND"
CDS_LIB"mstr_symbols";
"A\NAC"8;
%"GND"
"1","(-6425,4000)","0","mstr_symbols","I26";
;
VOLTAGE"0.0V"
SIZE"1B"
BODY_TYPE"PLUMBING"
HDL_POWER"GND"
CDS_LIB"mstr_symbols";
"A\NAC"9;
%"TPAD-DIFF-4P-GP"
"1","(-7975,6100)","0","w_hdl","I3";
;
CDS_SEC"1"
CDS_LOCATION"T1P1"
VALUE"TPAD-DIFF-4P-GP"
LOCATION"T1P1"
PART_NUMBER"ZZ.00PAD.NW1"
CDS_LMAN_SYM_OUTLINE"-75,100,75,-100"
CDS_LIB"w_hdl"
PACK_TYPE"DISCRET-GB3"
SEC"1"
SEC_TYPE"DISCRET-GB3";
"GND2"
$PN"GND2"12;
"GND1"
$PN"GND1"12;
"2"
$PN"2"63;
"1"
$PN"1"62;
%"TPAD-DIFF-4P-GP"
"1","(-4200,5675)","0","w_hdl","I30";
;
CDS_SEC"1"
CDS_LOCATION"T1P14"
LOCATION"T1P14"
VALUE"TPAD-DIFF-4P-GP"
PART_NUMBER"ZZ.00PAD.NW1"
CDS_LMAN_SYM_OUTLINE"-75,100,75,-100"
CDS_LIB"w_hdl"
PACK_TYPE"DISCRET-GB3"
SEC"1"
SEC_TYPE"DISCRET-GB3";
"GND2"
$PN"GND2"10;
"GND1"
$PN"GND1"10;
"2"
$PN"2"33;
"1"
$PN"1"34;
%"GND"
"1","(-4650,5525)","0","mstr_symbols","I32";
;
VOLTAGE"0.0V"
SIZE"1B"
BODY_TYPE"PLUMBING"
HDL_POWER"GND"
CDS_LIB"mstr_symbols";
"A\NAC"10;
%"TPAD-DIFF-4P-GP"
"1","(-4175,4550)","0","w_hdl","I36";
;
CDS_SEC"1"
CDS_LOCATION"T1P17"
LOCATION"T1P17"
VALUE"TPAD-DIFF-4P-GP"
PART_NUMBER"ZZ.00PAD.NW1"
CDS_LMAN_SYM_OUTLINE"-75,100,75,-100"
CDS_LIB"w_hdl"
PACK_TYPE"DISCRET-GB3"
SEC"1"
SEC_TYPE"DISCRET-GB3";
"GND2"
$PN"GND2"11;
"GND1"
$PN"GND1"11;
"2"
$PN"2"36;
"1"
$PN"1"35;
%"GND"
"1","(-4625,4400)","0","mstr_symbols","I37";
;
VOLTAGE"0.0V"
SIZE"1B"
BODY_TYPE"PLUMBING"
HDL_POWER"GND"
CDS_LIB"mstr_symbols";
"A\NAC"11;
%"TPAD-DIFF-4P-GP"
"1","(-2375,4200)","0","w_hdl","I38";
;
CDS_SEC"1"
CDS_LOCATION"T1P24"
LOCATION"T1P24"
VALUE"TPAD-DIFF-4P-GP"
PART_NUMBER"ZZ.00PAD.NW1"
CDS_LMAN_SYM_OUTLINE"-75,100,75,-100"
CDS_LIB"w_hdl"
PACK_TYPE"DISCRET-GB3"
SEC"1"
SEC_TYPE"DISCRET-GB3";
"GND2"
$PN"GND2"16;
"GND1"
$PN"GND1"16;
"2"
$PN"2"67;
"1"
$PN"1"42;
%"TPAD-DIFF-4P-GP"
"1","(-2400,6125)","0","w_hdl","I39";
;
CDS_SEC"1"
CDS_LOCATION"T1P19"
LOCATION"T1P19"
VALUE"TPAD-DIFF-4P-GP"
PART_NUMBER"ZZ.00PAD.NW1"
CDS_LMAN_SYM_OUTLINE"-75,100,75,-100"
CDS_LIB"w_hdl"
PACK_TYPE"DISCRET-GB3"
SEC"1"
SEC_TYPE"DISCRET-GB3";
"GND2"
$PN"GND2"13;
"GND1"
$PN"GND1"13;
"2"
$PN"2"77;
"1"
$PN"1"78;
%"GND"
"1","(-8425,5950)","0","mstr_symbols","I4";
;
VOLTAGE"0.0V"
SIZE"1B"
BODY_TYPE"PLUMBING"
HDL_POWER"GND"
CDS_LIB"mstr_symbols";
"A\NAC"12;
%"GND"
"1","(-2850,5975)","0","mstr_symbols","I40";
;
VOLTAGE"0.0V"
SIZE"1B"
BODY_TYPE"PLUMBING"
HDL_POWER"GND"
CDS_LIB"mstr_symbols";
"A\NAC"13;
%"TPAD-DIFF-4P-GP"
"1","(-2400,4950)","0","w_hdl","I45";
;
CDS_SEC"1"
CDS_LOCATION"T1P22"
LOCATION"T1P22"
VALUE"TPAD-DIFF-4P-GP"
PART_NUMBER"ZZ.00PAD.NW1"
CDS_LMAN_SYM_OUTLINE"-75,100,75,-100"
CDS_LIB"w_hdl"
PACK_TYPE"DISCRET-GB3"
SEC"1"
SEC_TYPE"DISCRET-GB3";
"GND2"
$PN"GND2"14;
"GND1"
$PN"GND1"14;
"2"
$PN"2"76;
"1"
$PN"1"68;
%"GND"
"1","(-2850,4800)","0","mstr_symbols","I46";
;
VOLTAGE"0.0V"
SIZE"1B"
BODY_TYPE"PLUMBING"
HDL_POWER"GND"
CDS_LIB"mstr_symbols";
"A\NAC"14;
%"TPAD-DIFF-4P-GP"
"1","(-2375,4600)","0","w_hdl","I47";
;
CDS_SEC"1"
CDS_LOCATION"T1P23"
VALUE"TPAD-DIFF-4P-GP"
LOCATION"T1P23"
PART_NUMBER"ZZ.00PAD.NW1"
CDS_LMAN_SYM_OUTLINE"-75,100,75,-100"
CDS_LIB"w_hdl"
PACK_TYPE"DISCRET-GB3"
SEC"1"
SEC_TYPE"DISCRET-GB3";
"GND2"
$PN"GND2"15;
"GND1"
$PN"GND1"15;
"2"
$PN"2"69;
"1"
$PN"1"70;
%"GND"
"1","(-2825,4450)","0","mstr_symbols","I48";
;
VOLTAGE"0.0V"
SIZE"1B"
BODY_TYPE"PLUMBING"
HDL_POWER"GND"
CDS_LIB"mstr_symbols";
"A\NAC"15;
%"GND"
"1","(-2825,4050)","0","mstr_symbols","I49";
;
VOLTAGE"0.0V"
SIZE"1B"
BODY_TYPE"PLUMBING"
HDL_POWER"GND"
CDS_LIB"mstr_symbols";
"A\NAC"16;
%"TPAD-DIFF-4P-GP"
"1","(-7975,5700)","0","w_hdl","I5";
;
CDS_SEC"1"
CDS_LOCATION"T1P2"
LOCATION"T1P2"
VALUE"TPAD-DIFF-4P-GP"
PART_NUMBER"ZZ.00PAD.NW1"
CDS_LMAN_SYM_OUTLINE"-75,100,75,-100"
CDS_LIB"w_hdl"
PACK_TYPE"DISCRET-GB3"
SEC"1"
SEC_TYPE"DISCRET-GB3";
"GND2"
$PN"GND2"23;
"GND1"
$PN"GND1"23;
"2"
$PN"2"31;
"1"
$PN"1"66;
%"TPAD-SE-2P-GP"
"1","(-8300,3500)","2","w_hdl","I50";
;
CDS_SEC"1"
$SEC"1"
CDS_LOCATION"T1P25"
LOCATION"T1P25"
VALUE"TPAD-SE-2P-GP"
PACK_TYPE"DISCRET-GA1"
PART_NUMBER"ZZ.00PAD.NU1"
CDS_LIB"w_hdl"
CDS_LMAN_SYM_OUTLINE"-75,100,75,-100";
"GND1"
$PN"GND1"17;
"1"
$PN"1"51;
%"GND"
"1","(-8000,3300)","0","mstr_symbols","I51";
;
VOLTAGE"0.0V"
SIZE"1B"
BODY_TYPE"PLUMBING"
HDL_POWER"GND"
CDS_LIB"mstr_symbols";
"A\NAC"17;
%"TPAD-SE-2P-GP"
"1","(-8300,3100)","2","w_hdl","I52";
;
CDS_SEC"1"
$SEC"1"
CDS_LOCATION"T1P26"
VALUE"TPAD-SE-2P-GP"
LOCATION"T1P26"
PACK_TYPE"DISCRET-GA1"
PART_NUMBER"ZZ.00PAD.NU1"
CDS_LMAN_SYM_OUTLINE"-75,100,75,-100"
CDS_LIB"w_hdl";
"GND1"
$PN"GND1"18;
"1"
$PN"1"55;
%"GND"
"1","(-8000,2900)","0","mstr_symbols","I53";
;
VOLTAGE"0.0V"
SIZE"1B"
BODY_TYPE"PLUMBING"
HDL_POWER"GND"
CDS_LIB"mstr_symbols";
"A\NAC"18;
%"TPAD-SE-2P-GP"
"1","(-8300,2625)","2","w_hdl","I54";
;
CDS_SEC"1"
$SEC"1"
CDS_LOCATION"T1P27"
VALUE"TPAD-SE-2P-GP"
LOCATION"T1P27"
PACK_TYPE"DISCRET-GA1"
PART_NUMBER"ZZ.00PAD.NU1"
CDS_LMAN_SYM_OUTLINE"-75,100,75,-100"
CDS_LIB"w_hdl";
"GND1"
$PN"GND1"19;
"1"
$PN"1"32;
%"GND"
"1","(-8000,2425)","0","mstr_symbols","I55";
;
VOLTAGE"0.0V"
SIZE"1B"
BODY_TYPE"PLUMBING"
HDL_POWER"GND"
CDS_LIB"mstr_symbols";
"A\NAC"19;
%"TPAD-SE-2P-GP"
"1","(-6525,3075)","2","w_hdl","I56";
;
CDS_SEC"1"
$SEC"1"
CDS_LOCATION"T1P29"
VALUE"TPAD-SE-2P-GP"
LOCATION"T1P29"
PACK_TYPE"DISCRET-GA1"
PART_NUMBER"ZZ.00PAD.NU1"
CDS_LMAN_SYM_OUTLINE"-75,100,75,-100"
CDS_LIB"w_hdl";
"GND1"
$PN"GND1"21;
"1"
$PN"1"53;
%"GND"
"1","(-6225,3275)","0","mstr_symbols","I57";
;
VOLTAGE"0.0V"
SIZE"1B"
BODY_TYPE"PLUMBING"
HDL_POWER"GND"
CDS_LIB"mstr_symbols";
"A\NAC"20;
%"GND"
"1","(-6225,2875)","0","mstr_symbols","I58";
;
VOLTAGE"0.0V"
SIZE"1B"
BODY_TYPE"PLUMBING"
HDL_POWER"GND"
CDS_LIB"mstr_symbols";
"A\NAC"21;
%"GND"
"1","(-6225,2400)","0","mstr_symbols","I59";
;
VOLTAGE"0.0V"
SIZE"1B"
BODY_TYPE"PLUMBING"
HDL_POWER"GND"
CDS_LIB"mstr_symbols";
"A\NAC"22;
%"GND"
"1","(-8425,5550)","0","mstr_symbols","I6";
;
VOLTAGE"0.0V"
SIZE"1B"
BODY_TYPE"PLUMBING"
HDL_POWER"GND"
CDS_LIB"mstr_symbols";
"A\NAC"23;
%"TPAD-SE-2P-GP"
"1","(-6525,3475)","2","w_hdl","I60";
;
CDS_SEC"1"
$SEC"1"
CDS_LOCATION"T1P28"
VALUE"TPAD-SE-2P-GP"
LOCATION"T1P28"
PACK_TYPE"DISCRET-GA1"
PART_NUMBER"ZZ.00PAD.NU1"
CDS_LIB"w_hdl"
CDS_LMAN_SYM_OUTLINE"-75,100,75,-100";
"GND1"
$PN"GND1"20;
"1"
$PN"1"54;
%"TPAD-SE-2P-GP"
"1","(-6525,2600)","2","w_hdl","I61";
;
CDS_SEC"1"
$SEC"1"
CDS_LOCATION"T1P30"
VALUE"TPAD-SE-2P-GP"
LOCATION"T1P30"
PACK_TYPE"DISCRET-GA1"
PART_NUMBER"ZZ.00PAD.NU1"
CDS_LMAN_SYM_OUTLINE"-75,100,75,-100"
CDS_LIB"w_hdl";
"GND1"
$PN"GND1"22;
"1"
$PN"1"52;
%"TPAD-SE-2P-GP"
"1","(-2750,3450)","2","w_hdl","I62";
;
CDS_SEC"1"
$SEC"1"
CDS_LOCATION"T1P34"
VALUE"TPAD-SE-2P-GP"
LOCATION"T1P34"
CDS_LMAN_SYM_OUTLINE"-75,100,75,-100"
CDS_LIB"w_hdl"
PART_NUMBER"ZZ.00PAD.NU1"
PACK_TYPE"DISCRET-GA1";
"GND1"
$PN"GND1"25;
"1"
$PN"1"41;
%"TPAD-SE-2P-GP"
"1","(-2750,2575)","2","w_hdl","I63";
;
CDS_SEC"1"
$SEC"1"
CDS_LOCATION"T1P36"
VALUE"TPAD-SE-2P-GP"
LOCATION"T1P36"
CDS_LIB"w_hdl"
CDS_LMAN_SYM_OUTLINE"-75,100,75,-100"
PART_NUMBER"ZZ.00PAD.NU1"
PACK_TYPE"DISCRET-GA1";
"GND1"
$PN"GND1"24;
"1"
$PN"1"39;
%"GND"
"1","(-2450,2375)","0","mstr_symbols","I64";
;
CDS_LIB"mstr_symbols"
HDL_POWER"GND"
BODY_TYPE"PLUMBING"
SIZE"1B"
VOLTAGE"0.0V";
"A\NAC"24;
%"GND"
"1","(-2450,3250)","0","mstr_symbols","I65";
;
CDS_LIB"mstr_symbols"
HDL_POWER"GND"
BODY_TYPE"PLUMBING"
SIZE"1B"
VOLTAGE"0.0V";
"A\NAC"25;
%"GND"
"1","(-2450,2850)","0","mstr_symbols","I66";
;
CDS_LIB"mstr_symbols"
HDL_POWER"GND"
BODY_TYPE"PLUMBING"
SIZE"1B"
VOLTAGE"0.0V";
"A\NAC"26;
%"TPAD-SE-2P-GP"
"1","(-2750,3050)","2","w_hdl","I67";
;
CDS_SEC"1"
$SEC"1"
CDS_LOCATION"T1P35"
VALUE"TPAD-SE-2P-GP"
LOCATION"T1P35"
CDS_LIB"w_hdl"
CDS_LMAN_SYM_OUTLINE"-75,100,75,-100"
PART_NUMBER"ZZ.00PAD.NU1"
PACK_TYPE"DISCRET-GA1";
"GND1"
$PN"GND1"26;
"1"
$PN"1"40;
%"GND"
"1","(-4225,3275)","0","mstr_symbols","I68";
;
CDS_LIB"mstr_symbols"
HDL_POWER"GND"
BODY_TYPE"PLUMBING"
SIZE"1B"
VOLTAGE"0.0V";
"A\NAC"27;
%"GND"
"1","(-4225,2875)","0","mstr_symbols","I69";
;
CDS_LIB"mstr_symbols"
HDL_POWER"GND"
BODY_TYPE"PLUMBING"
SIZE"1B"
VOLTAGE"0.0V";
"A\NAC"28;
%"TPAD-DIFF-4P-GP"
"1","(-7975,4925)","0","w_hdl","I7";
;
CDS_SEC"1"
CDS_LOCATION"T1P4"
LOCATION"T1P4"
VALUE"TPAD-DIFF-4P-GP"
PART_NUMBER"ZZ.00PAD.NW1"
CDS_LMAN_SYM_OUTLINE"-75,100,75,-100"
CDS_LIB"w_hdl"
PACK_TYPE"DISCRET-GB3"
SEC"1"
SEC_TYPE"DISCRET-GB3";
"GND2"
$PN"GND2"1;
"GND1"
$PN"GND1"1;
"2"
$PN"2"49;
"1"
$PN"1"48;
%"GND"
"1","(-4225,2400)","0","mstr_symbols","I70";
;
CDS_LIB"mstr_symbols"
HDL_POWER"GND"
BODY_TYPE"PLUMBING"
SIZE"1B"
VOLTAGE"0.0V";
"A\NAC"29;
%"TPAD-SE-2P-GP"
"1","(-4525,3475)","2","w_hdl","I71";
;
CDS_SEC"1"
$SEC"1"
CDS_LOCATION"T1P31"
VALUE"TPAD-SE-2P-GP"
LOCATION"T1P31"
CDS_LMAN_SYM_OUTLINE"-75,100,75,-100"
CDS_LIB"w_hdl"
PART_NUMBER"ZZ.00PAD.NU1"
PACK_TYPE"DISCRET-GA1";
"GND1"
$PN"GND1"27;
"1"
$PN"1"37;
%"TPAD-SE-2P-GP"
"1","(-4525,3075)","2","w_hdl","I72";
;
CDS_SEC"1"
$SEC"1"
CDS_LOCATION"T1P32"
VALUE"TPAD-SE-2P-GP"
LOCATION"T1P32"
CDS_LIB"w_hdl"
CDS_LMAN_SYM_OUTLINE"-75,100,75,-100"
PART_NUMBER"ZZ.00PAD.NU1"
PACK_TYPE"DISCRET-GA1";
"GND1"
$PN"GND1"28;
"1"
$PN"1"38;
%"TPAD-SE-2P-GP"
"1","(-4525,2600)","2","w_hdl","I73";
;
CDS_SEC"1"
$SEC"1"
CDS_LOCATION"T1P33"
VALUE"TPAD-SE-2P-GP"
LOCATION"T1P33"
CDS_LIB"w_hdl"
CDS_LMAN_SYM_OUTLINE"-75,100,75,-100"
PART_NUMBER"ZZ.00PAD.NU1"
PACK_TYPE"DISCRET-GA1";
"GND1"
$PN"GND1"29;
"1"
$PN"1"46;
%"TPAD-DIFF-4P-GP"
"1","(-7975,5325)","0","w_hdl","I8";
;
CDS_SEC"1"
CDS_LOCATION"T1P3"
VALUE"TPAD-DIFF-4P-GP"
LOCATION"T1P3"
PART_NUMBER"ZZ.00PAD.NW1"
CDS_LMAN_SYM_OUTLINE"-75,100,75,-100"
CDS_LIB"w_hdl"
PACK_TYPE"DISCRET-GB3"
SEC"1"
SEC_TYPE"DISCRET-GB3";
"GND2"
$PN"GND2"30;
"GND1"
$PN"GND1"30;
"2"
$PN"2"65;
"1"
$PN"1"64;
%"GND"
"1","(-8425,5175)","0","mstr_symbols","I9";
;
VOLTAGE"0.0V"
SIZE"1B"
BODY_TYPE"PLUMBING"
HDL_POWER"GND"
CDS_LIB"mstr_symbols";
"A\NAC"30;
END.
